(kicad_pcb
	(version 20241229)
	(generator "pcbnew")
	(generator_version "9.0")
	(general
		(thickness 1.711)
		(legacy_teardrops no)
	)
	(paper "A4")
	(title_block
		(title "Antmicro Baseboard for Jetson AGX Thor")
		(date "2026-02-18")
		(rev "1.1.0")
		(company "Antmicro Ltd")
		(comment 1 "www.antmicro.com")
		(comment 9 "footprints 967-971 of 1170")
	)
	(layers
		(0 "F.Cu" signal)
		(4 "In1.Cu" signal)
		(6 "In2.Cu" signal)
		(8 "In3.Cu" signal)
		(10 "In4.Cu" jumper)
		(12 "In5.Cu" signal)
		(14 "In6.Cu" signal)
		(16 "In7.Cu" signal)
		(18 "In8.Cu" signal)
		(2 "B.Cu" signal)
		(9 "F.Adhes" user "F.Adhesive")
		(11 "B.Adhes" user "B.Adhesive")
		(13 "F.Paste" user)
		(15 "B.Paste" user)
		(5 "F.SilkS" user "F.Silkscreen")
		(7 "B.SilkS" user "B.Silkscreen")
		(1 "F.Mask" user)
		(3 "B.Mask" user)
		(17 "Dwgs.User" user "User.Drawings")
		(19 "Cmts.User" user "User.Comments")
		(21 "Eco1.User" user "User.Eco1")
		(23 "Eco2.User" user "User.Eco2")
		(25 "Edge.Cuts" user)
		(27 "Margin" user)
		(31 "F.CrtYd" user "F.Courtyard")
		(29 "B.CrtYd" user "B.Courtyard")
		(35 "F.Fab" user)
		(33 "B.Fab" user)
	)
	(footprint "antmicro-footprints:TP_SMD_0.75mm"
		(layer "B.Cu")
		(at 234 127 180)
		(property "Reference" "TP44"
			(at -3.5 -0.3 0)
			(layer "B.SilkS")
			(effects
				(font
					(size 0.7 0.7)
					(thickness 0.15)
				)
				(justify left bottom mirror)
			)
		)
		(property "Value" "TP_0.75mm_SMD"
			(at 0 -1.2 0)
			(layer "B.Fab")
			(effects
				(font
					(size 0.7 0.7)
					(thickness 0.15)
				)
				(justify left bottom mirror)
			)
		)
		(property "Description" "SMT test point"
			(at 0 0 0)
			(layer "B.Fab")
			(hide yes)
			(effects
				(font
					(size 1.27 1.27)
					(thickness 0.15)
				)
				(justify mirror)
			)
		)
		(property "MPN" ""
			(at 0 0 0)
			(unlocked yes)
			(layer "B.Fab")
			(hide yes)
			(effects
				(font
					(size 1 1)
					(thickness 0.15)
				)
				(justify mirror)
			)
		)
		(property "Manufacturer" ""
			(at 0 0 0)
			(unlocked yes)
			(layer "B.Fab")
			(hide yes)
			(effects
				(font
					(size 1 1)
					(thickness 0.15)
				)
				(justify mirror)
			)
		)
		(property "Author" "Antmicro"
			(at 0 0 0)
			(unlocked yes)
			(layer "B.Fab")
			(hide yes)
			(effects
				(font
					(size 1 1)
					(thickness 0.15)
				)
				(justify mirror)
			)
		)
		(property "License" "Apache-2.0"
			(at 0 0 0)
			(unlocked yes)
			(layer "B.Fab")
			(hide yes)
			(effects
				(font
					(size 1 1)
					(thickness 0.15)
				)
				(justify mirror)
			)
		)
		(sheetname "/USB Hub/")
		(sheetfile "usb_hub.kicad_sch")
		(attr exclude_from_pos_files exclude_from_bom)
		(fp_circle
			(center 0 0)
			(end 0.475 0)
			(stroke
				(width 0.05)
				(type default)
			)
			(fill no)
			(layer "B.CrtYd")
		)
		(fp_text user "License: Apache-2.0"
			(at -0.4 -5.101 0)
			(layer "B.Fab")
			(effects
				(font
					(size 0.7 0.7)
					(thickness 0.15)
				)
				(justify left bottom mirror)
			)
		)
		(fp_text user "${REFERENCE}"
			(at -0.4 -2.7 0)
			(layer "B.Fab")
			(effects
				(font
					(size 0.7 0.7)
					(thickness 0.15)
				)
				(justify left bottom mirror)
			)
		)
		(fp_text user "Author: Antmicro"
			(at -0.4 -3.901 0)
			(layer "B.Fab")
			(effects
				(font
					(size 0.7 0.7)
					(thickness 0.15)
				)
				(justify left bottom mirror)
			)
		)
		(pad "1" smd circle
			(at 0 0 180)
			(size 0.75 0.75)
			(layers "B.Cu" "B.Mask")
			(net 115 "/USB Hub/USBC4_VBUS")
			(pinfunction "1")
			(pintype "passive")
		)
	)
	(footprint "antmicro-footprints:C_0402_1005Metric"
		(layer "B.Cu")
		(at 219.52 75.1)
		(descr "Capacitor SMD 0402")
		(tags "capacitor SMD 0402")
		(property "Reference" "C133"
			(at -0.72 -1.4 0)
			(layer "B.SilkS")
			(effects
				(font
					(size 0.7 0.7)
					(thickness 0.15)
				)
				(justify right top mirror)
			)
		)
		(property "Value" "C_100n_0402"
			(at -1.022927 -2.155213 0)
			(layer "B.Fab")
			(effects
				(font
					(size 0.7 0.7)
					(thickness 0.15)
				)
				(justify right top mirror)
			)
		)
		(property "Datasheet" "https://www.murata.com/products/productdetail?partno=GRM155R61H104KE14%23"
			(at 0 0 0)
			(layer "B.Fab")
			(hide yes)
			(effects
				(font
					(size 1.27 1.27)
					(thickness 0.15)
				)
				(justify mirror)
			)
		)
		(property "Description" "SMD Multilayer Ceramic Capacitor, 0.1 µF, 50 V, 0402 [1005 Metric], ± 10%, X5R, GRM Series"
			(at 0 0 0)
			(layer "B.Fab")
			(hide yes)
			(effects
				(font
					(size 1.27 1.27)
					(thickness 0.15)
				)
				(justify mirror)
			)
		)
		(property "Manufacturer" "Murata"
			(at 0 0 180)
			(unlocked yes)
			(layer "B.Fab")
			(hide yes)
			(effects
				(font
					(size 1 1)
					(thickness 0.15)
				)
				(justify mirror)
			)
		)
		(property "MPN" "GRM155R61H104KE14D"
			(at 0 0 180)
			(unlocked yes)
			(layer "B.Fab")
			(hide yes)
			(effects
				(font
					(size 1 1)
					(thickness 0.15)
				)
				(justify mirror)
			)
		)
		(property "Val" "100n"
			(at 0 0 180)
			(unlocked yes)
			(layer "B.Fab")
			(hide yes)
			(effects
				(font
					(size 1 1)
					(thickness 0.15)
				)
				(justify mirror)
			)
		)
		(property "License" "Apache-2.0"
			(at 0 0 180)
			(unlocked yes)
			(layer "B.Fab")
			(hide yes)
			(effects
				(font
					(size 1 1)
					(thickness 0.15)
				)
				(justify mirror)
			)
		)
		(property "Author" "Antmicro"
			(at 0 0 180)
			(unlocked yes)
			(layer "B.Fab")
			(hide yes)
			(effects
				(font
					(size 1 1)
					(thickness 0.15)
				)
				(justify mirror)
			)
		)
		(property "Voltage" "50V"
			(at 0 0 180)
			(unlocked yes)
			(layer "B.Fab")
			(hide yes)
			(effects
				(font
					(size 1 1)
					(thickness 0.15)
				)
				(justify mirror)
			)
		)
		(property "Dielectric" "X5R"
			(at 0 0 180)
			(unlocked yes)
			(layer "B.Fab")
			(hide yes)
			(effects
				(font
					(size 1 1)
					(thickness 0.15)
				)
				(justify mirror)
			)
		)
		(sheetname "/USB Debug, PD/")
		(sheetfile "usb_debug_pd.kicad_sch")
		(attr smd)
		(fp_poly
			(pts
				(xy -0.925 0.47) (xy -0.925 -0.47) (xy 0.925 -0.47) (xy 0.925 0.47)
			)
			(stroke
				(width 0.05)
				(type default)
			)
			(fill no)
			(layer "B.CrtYd")
		)
		(fp_line
			(start -0.494 -0.248)
			(end -0.494 0.25)
			(stroke
				(width 0.15)
				(type solid)
			)
			(layer "B.Fab")
		)
		(fp_line
			(start -0.494 0.25)
			(end 0.504 0.25)
			(stroke
				(width 0.15)
				(type solid)
			)
			(layer "B.Fab")
		)
		(fp_line
			(start 0.504 -0.248)
			(end -0.494 -0.248)
			(stroke
				(width 0.15)
				(type solid)
			)
			(layer "B.Fab")
		)
		(fp_line
			(start 0.504 0.25)
			(end 0.504 -0.248)
			(stroke
				(width 0.15)
				(type solid)
			)
			(layer "B.Fab")
		)
		(fp_text user "Author: Antmicro"
			(at -0.939 -3.399 0)
			(layer "B.Fab")
			(effects
				(font
					(size 0.7 0.7)
					(thickness 0.15)
				)
				(justify right top mirror)
			)
		)
		(fp_text user "License: Apache-2.0"
			(at -0.939 -5.799 0)
			(layer "B.Fab")
			(effects
				(font
					(size 0.7 0.7)
					(thickness 0.15)
				)
				(justify right top mirror)
			)
		)
		(fp_text user "${REFERENCE}"
			(at -0.939 -4.599 0)
			(layer "B.Fab")
			(effects
				(font
					(size 0.7 0.7)
					(thickness 0.15)
				)
				(justify right top mirror)
			)
		)
		(pad "1" smd roundrect
			(at -0.48 0)
			(size 0.59 0.64)
			(layers "B.Cu" "B.Mask" "B.Paste")
			(roundrect_rratio 0.25)
			(net 334 "/USB Debug, PD/FTDI_3V3")
			(pintype "passive")
		)
		(pad "2" smd roundrect
			(at 0.48 0)
			(size 0.59 0.64)
			(layers "B.Cu" "B.Mask" "B.Paste")
			(roundrect_rratio 0.25)
			(net 1 "GND")
			(pintype "passive")
		)
	)
	(footprint "antmicro-footprints:C_0402_1005Metric"
		(layer "B.Cu")
		(at 180.24 88.85)
		(descr "Capacitor SMD 0402")
		(tags "capacitor SMD 0402")
		(property "Reference" "C265"
			(at -5.54 -0.35 0)
			(layer "B.SilkS")
			(effects
				(font
					(size 0.7 0.7)
					(thickness 0.15)
				)
				(justify right top mirror)
			)
		)
		(property "Value" "C_1u_25V_0402"
			(at -1.022927 -2.155213 0)
			(layer "B.Fab")
			(effects
				(font
					(size 0.7 0.7)
					(thickness 0.15)
				)
				(justify right top mirror)
			)
		)
		(property "Datasheet" "https://www.murata.com/products/productdetail?partno=GRM155R61E105KE11%23"
			(at 0 0 0)
			(layer "B.Fab")
			(hide yes)
			(effects
				(font
					(size 1.27 1.27)
					(thickness 0.15)
				)
				(justify mirror)
			)
		)
		(property "Description" "SMD Multilayer Ceramic Capacitor, 1 µF, 25 V, 0402 [1005 Metric], ± 10%, X5R, GRM Series"
			(at 0 0 0)
			(layer "B.Fab")
			(hide yes)
			(effects
				(font
					(size 1.27 1.27)
					(thickness 0.15)
				)
				(justify mirror)
			)
		)
		(property "MPN" "GRM155R61E105KE11J"
			(at 0 0 180)
			(unlocked yes)
			(layer "B.Fab")
			(hide yes)
			(effects
				(font
					(size 1 1)
					(thickness 0.15)
				)
				(justify mirror)
			)
		)
		(property "Manufacturer" "Murata"
			(at 0 0 180)
			(unlocked yes)
			(layer "B.Fab")
			(hide yes)
			(effects
				(font
					(size 1 1)
					(thickness 0.15)
				)
				(justify mirror)
			)
		)
		(property "License" "Apache-2.0"
			(at 0 0 180)
			(unlocked yes)
			(layer "B.Fab")
			(hide yes)
			(effects
				(font
					(size 1 1)
					(thickness 0.15)
				)
				(justify mirror)
			)
		)
		(property "Author" "Antmicro"
			(at 0 0 180)
			(unlocked yes)
			(layer "B.Fab")
			(hide yes)
			(effects
				(font
					(size 1 1)
					(thickness 0.15)
				)
				(justify mirror)
			)
		)
		(property "Val" "1u"
			(at 0 0 180)
			(unlocked yes)
			(layer "B.Fab")
			(hide yes)
			(effects
				(font
					(size 1 1)
					(thickness 0.15)
				)
				(justify mirror)
			)
		)
		(property "Voltage" "25V"
			(at 0 0 180)
			(unlocked yes)
			(layer "B.Fab")
			(hide yes)
			(effects
				(font
					(size 1 1)
					(thickness 0.15)
				)
				(justify mirror)
			)
		)
		(property "Dielectric" "X5R"
			(at 0 0 180)
			(unlocked yes)
			(layer "B.Fab")
			(hide yes)
			(effects
				(font
					(size 1 1)
					(thickness 0.15)
				)
				(justify mirror)
			)
		)
		(sheetname "/Power/")
		(sheetfile "power.kicad_sch")
		(attr smd)
		(fp_rect
			(start -0.925 0.47)
			(end 0.925 -0.47)
			(stroke
				(width 0.05)
				(type default)
			)
			(fill no)
			(layer "B.CrtYd")
		)
		(fp_line
			(start -0.494 -0.248)
			(end -0.494 0.25)
			(stroke
				(width 0.15)
				(type solid)
			)
			(layer "B.Fab")
		)
		(fp_line
			(start -0.494 0.25)
			(end 0.504 0.25)
			(stroke
				(width 0.15)
				(type solid)
			)
			(layer "B.Fab")
		)
		(fp_line
			(start 0.504 -0.248)
			(end -0.494 -0.248)
			(stroke
				(width 0.15)
				(type solid)
			)
			(layer "B.Fab")
		)
		(fp_line
			(start 0.504 0.25)
			(end 0.504 -0.248)
			(stroke
				(width 0.15)
				(type solid)
			)
			(layer "B.Fab")
		)
		(fp_text user "License: Apache-2.0"
			(at -0.939 -5.799 0)
			(layer "B.Fab")
			(effects
				(font
					(size 0.7 0.7)
					(thickness 0.15)
				)
				(justify right top mirror)
			)
		)
		(fp_text user "${REFERENCE}"
			(at -0.939 -4.599 0)
			(layer "B.Fab")
			(effects
				(font
					(size 0.7 0.7)
					(thickness 0.15)
				)
				(justify right top mirror)
			)
		)
		(fp_text user "Author: Antmicro"
			(at -0.939 -3.399 0)
			(layer "B.Fab")
			(effects
				(font
					(size 0.7 0.7)
					(thickness 0.15)
				)
				(justify right top mirror)
			)
		)
		(pad "1" smd roundrect
			(at -0.48 0)
			(size 0.59 0.64)
			(layers "B.Cu" "B.Mask" "B.Paste")
			(roundrect_rratio 0.25)
			(net 1 "GND")
			(pintype "passive")
		)
		(pad "2" smd roundrect
			(at 0.48 0)
			(size 0.59 0.64)
			(layers "B.Cu" "B.Mask" "B.Paste")
			(roundrect_rratio 0.25)
			(net 522 "/Power/USBPD1_HV")
			(pintype "passive")
		)
	)
	(footprint "antmicro-footprints:R_0402_1005Metric"
		(layer "B.Cu")
		(at 207.8 81.3 180)
		(descr "Resistor SMD 0402")
		(tags "resistor SMD 0402")
		(property "Reference" "R96"
			(at -3.1 -1.4 0)
			(layer "B.SilkS")
			(effects
				(font
					(size 0.7 0.7)
					(thickness 0.15)
				)
				(justify left bottom mirror)
			)
		)
		(property "Value" "R_10k_0402"
			(at -1.011843 -1.772046 0)
			(layer "B.Fab")
			(effects
				(font
					(size 0.7 0.7)
					(thickness 0.15)
				)
				(justify left bottom mirror)
			)
		)
		(property "Datasheet" "https://www.bourns.com/docs/product-datasheets/cr.pdf"
			(at 0 0 0)
			(layer "B.Fab")
			(hide yes)
			(effects
				(font
					(size 1.27 1.27)
					(thickness 0.15)
				)
				(justify mirror)
			)
		)
		(property "Description" "SMD Chip Resistor, 10 kohm, ± 1%, 62.5 mW, 0402 [1005 Metric], Thick Film, General Purpose"
			(at 0 0 0)
			(layer "B.Fab")
			(hide yes)
			(effects
				(font
					(size 1.27 1.27)
					(thickness 0.15)
				)
				(justify mirror)
			)
		)
		(property "Manufacturer" "Bourns"
			(at 0 0 0)
			(unlocked yes)
			(layer "B.Fab")
			(hide yes)
			(effects
				(font
					(size 1 1)
					(thickness 0.15)
				)
				(justify mirror)
			)
		)
		(property "MPN" "CR0402-FX-1002GLF"
			(at 0 0 0)
			(unlocked yes)
			(layer "B.Fab")
			(hide yes)
			(effects
				(font
					(size 1 1)
					(thickness 0.15)
				)
				(justify mirror)
			)
		)
		(property "Val" "10k"
			(at 0 0 0)
			(unlocked yes)
			(layer "B.Fab")
			(hide yes)
			(effects
				(font
					(size 1 1)
					(thickness 0.15)
				)
				(justify mirror)
			)
		)
		(property "License" "Apache-2.0"
			(at 0 0 0)
			(unlocked yes)
			(layer "B.Fab")
			(hide yes)
			(effects
				(font
					(size 1 1)
					(thickness 0.15)
				)
				(justify mirror)
			)
		)
		(property "Author" "Antmicro"
			(at 0 0 0)
			(unlocked yes)
			(layer "B.Fab")
			(hide yes)
			(effects
				(font
					(size 1 1)
					(thickness 0.15)
				)
				(justify mirror)
			)
		)
		(property "Tolerance" "1%"
			(at 0 0 0)
			(unlocked yes)
			(layer "B.Fab")
			(hide yes)
			(effects
				(font
					(size 1 1)
					(thickness 0.15)
				)
				(justify mirror)
			)
		)
		(sheetname "/USB Debug, PD/")
		(sheetfile "usb_debug_pd.kicad_sch")
		(attr smd)
		(fp_poly
			(pts
				(xy -0.925 0.47) (xy 0.925 0.47) (xy 0.925 -0.47) (xy -0.925 -0.47)
			)
			(stroke
				(width 0.05)
				(type default)
			)
			(fill no)
			(layer "B.CrtYd")
		)
		(fp_poly
			(pts
				(xy -0.5 0.25) (xy 0.5 0.25) (xy 0.5 -0.25) (xy -0.5 -0.25)
			)
			(stroke
				(width 0.15)
				(type solid)
			)
			(fill no)
			(layer "B.Fab")
		)
		(fp_text user "Author: Antmicro"
			(at -0.95 -4.169 0)
			(layer "B.Fab")
			(effects
				(font
					(size 0.7 0.7)
					(thickness 0.15)
				)
				(justify left bottom mirror)
			)
		)
		(fp_text user "License: Apache-2.0"
			(at -0.949999 -5.169 0)
			(layer "B.Fab")
			(effects
				(font
					(size 0.7 0.7)
					(thickness 0.15)
				)
				(justify left bottom mirror)
			)
		)
		(fp_text user "${REFERENCE}"
			(at -0.95 -3.168 0)
			(layer "B.Fab")
			(effects
				(font
					(size 0.7 0.7)
					(thickness 0.15)
				)
				(justify left bottom mirror)
			)
		)
		(pad "1" smd roundrect
			(at -0.48 0 180)
			(size 0.59 0.64)
			(layers "B.Cu" "B.Mask" "B.Paste")
			(roundrect_rratio 0.25)
			(net 294 "/USB Debug, PD/PDC_LDO_3V3")
			(pintype "passive")
		)
		(pad "2" smd roundrect
			(at 0.48 0 180)
			(size 0.59 0.64)
			(layers "B.Cu" "B.Mask" "B.Paste")
			(roundrect_rratio 0.25)
			(net 935 "/USB Debug, PD/PDC_ADCIN2")
			(pintype "passive")
		)
	)
	(footprint "antmicro-footprints:TP_SMD_0.75mm"
		(layer "B.Cu")
		(at 63.5 120.5)
		(property "Reference" "TP114"
			(at -0.5 2.200001 0)
			(layer "B.SilkS")
			(effects
				(font
					(size 0.7 0.7)
					(thickness 0.15)
				)
				(justify right top mirror)
			)
		)
		(property "Value" "TP_0.75mm_SMD"
			(at 0 -1.2 0)
			(layer "B.Fab")
			(effects
				(font
					(size 0.7 0.7)
					(thickness 0.15)
				)
				(justify right top mirror)
			)
		)
		(property "Description" "SMT test point"
			(at 0 0 0)
			(layer "B.Fab")
			(hide yes)
			(effects
				(font
					(size 1.27 1.27)
					(thickness 0.15)
				)
				(justify mirror)
			)
		)
		(property "MPN" ""
			(at 0 0 180)
			(unlocked yes)
			(layer "B.Fab")
			(hide yes)
			(effects
				(font
					(size 1 1)
					(thickness 0.15)
				)
				(justify mirror)
			)
		)
		(property "Manufacturer" ""
			(at 0 0 180)
			(unlocked yes)
			(layer "B.Fab")
			(hide yes)
			(effects
				(font
					(size 1 1)
					(thickness 0.15)
				)
				(justify mirror)
			)
		)
		(property "Author" "Antmicro"
			(at 0 0 180)
			(unlocked yes)
			(layer "B.Fab")
			(hide yes)
			(effects
				(font
					(size 1 1)
					(thickness 0.15)
				)
				(justify mirror)
			)
		)
		(property "License" "Apache-2.0"
			(at 0 0 180)
			(unlocked yes)
			(layer "B.Fab")
			(hide yes)
			(effects
				(font
					(size 1 1)
					(thickness 0.15)
				)
				(justify mirror)
			)
		)
		(sheetname "/Expansion connector/")
		(sheetfile "expansion_connector.kicad_sch")
		(attr exclude_from_pos_files exclude_from_bom)
		(fp_circle
			(center 0 0)
			(end 0.475 0)
			(stroke
				(width 0.05)
				(type default)
			)
			(fill no)
			(layer "B.CrtYd")
		)
		(fp_text user "Author: Antmicro"
			(at -0.4 -3.901 0)
			(layer "B.Fab")
			(effects
				(font
					(size 0.7 0.7)
					(thickness 0.15)
				)
				(justify right top mirror)
			)
		)
		(fp_text user "License: Apache-2.0"
			(at -0.4 -5.101 0)
			(layer "B.Fab")
			(effects
				(font
					(size 0.7 0.7)
					(thickness 0.15)
				)
				(justify right top mirror)
			)
		)
		(fp_text user "${REFERENCE}"
			(at -0.4 -2.7 0)
			(layer "B.Fab")
			(effects
				(font
					(size 0.7 0.7)
					(thickness 0.15)
				)
				(justify right top mirror)
			)
		)
		(pad "1" smd circle
			(at 0 0)
			(size 0.75 0.75)
			(layers "B.Cu" "B.Mask")
			(net 571 "Net-(J18-PadL32)")
			(pinfunction "1")
			(pintype "passive")
		)
	)
)
